# BASEBOARD_FAB2 (Tioga Pass) — schematic netlist excerpt (pin names and nets, part order shuffled) for the footprints in the layout excerpt that follows; sources: Cadence DE-HDL packaged netlist, KiCad conversion of Wiwynn_Tioga_Pass_MB.brd

R6W21  RES  1.00K 1% CHIP  pkg 0402  page 247 : A = P3V3_STBY ; B = PU_ID_EEPROM_A0
C9P3  CAP_A  22.0UF 4V 20% X6S  pkg 0603V  page 207 : A = PVCCIN_CPU1 ; B = GND
C3L20  CAPP  470UF 2V 20% ALUM  pkg SM  page 236 : A = PVNN_PCH_STBY ; B = GND

(kicad_pcb
	(version 20260206)
	(generator "pcbnew")
	(generator_version "10.0")
	(general
		(thickness 1.6)
		(legacy_teardrops no)
	)
	(paper "A4")
	(title_block
		(title "Wiwynn_Tioga_Pass_MB.brd")
		(comment 1 "Tioga Pass / footprints 4637-4639 of 4770")
	)
	(layers
		(0 "F.Cu" signal "TOP")
		(4 "In1.Cu" signal "L2GND")
		(6 "In2.Cu" signal "L3")
		(8 "In3.Cu" signal "L4GND")
		(10 "In4.Cu" signal "L5")
		(12 "In5.Cu" signal "L6GND")
		(14 "In6.Cu" signal "L7VCC")
		(16 "In7.Cu" signal "L8VCC")
		(18 "In8.Cu" signal "L9GND")
		(20 "In9.Cu" signal "L10")
		(22 "In10.Cu" signal "L11GND")
		(24 "In11.Cu" signal "L12")
		(26 "In12.Cu" signal "L13GND")
		(2 "B.Cu" signal "BOTTOM")
		(9 "F.Adhes" user "F.Adhesive")
		(11 "B.Adhes" user "B.Adhesive")
		(13 "F.Paste" user "Package Geometry/Pastemask Top")
		(15 "B.Paste" user "Package Geometry/Pastemask Bottom")
		(5 "F.SilkS" user "Ref Des/Silkscreen Top")
		(7 "B.SilkS" user "Ref Des/Silkscreen Bottom")
		(1 "F.Mask" user "Board Geometry/Soldermask Top")
		(3 "B.Mask" user "Board Geometry/Soldermask Bottom")
		(17 "Dwgs.User" user "User.Drawings")
		(19 "Cmts.User" user "User.Comments")
		(21 "Eco1.User" user "User.Eco1")
		(23 "Eco2.User" user "User.Eco2")
		(25 "Edge.Cuts" user "Board Geometry/Outline")
		(27 "Margin" user)
		(31 "F.CrtYd" user "Package Geometry/Place Bound Top")
		(29 "B.CrtYd" user "Package Geometry/Place Bound Bottom")
		(35 "F.Fab" user "Ref Des/Assembly Top")
		(33 "B.Fab" user "Ref Des/Assembly Bottom")
	)
	(footprint ""
		(layer "B.Cu")
		(at 462.5975 -23.114 180)
		(property "Reference" "R6W21"
			(at 0.8382 -0.67818 180)
			(unlocked yes)
			(layer "B.SilkS")
			(effects
				(font
					(size 0.4064 0.254)
					(thickness 0.1524)
				)
				(justify left mirror)
			)
		)
		(property "Value" ""
			(at 0 0 0)
			(layer "B.Fab")
			(effects
				(font
					(size 1.27 1.27)
				)
				(justify mirror)
			)
		)
		(duplicate_pad_numbers_are_jumpers no)
		(fp_poly
			(pts
				(xy 0.2794 -0.1016) (xy -0.2794 -0.1016) (xy -0.2794 0.9906) (xy 0.2794 0.9906)
			)
			(stroke
				(width 0)
				(type default)
			)
			(fill no)
			(layer "B.CrtYd")
		)
		(fp_line
			(start 0.2794 0.9906)
			(end -0.2794 0.9906)
			(stroke
				(width 0.1)
				(type default)
			)
			(layer "B.Fab")
		)
		(fp_line
			(start 0.2794 -0.1016)
			(end 0.2794 0.9906)
			(stroke
				(width 0.1)
				(type default)
			)
			(layer "B.Fab")
		)
		(fp_line
			(start -0.2794 0.9906)
			(end -0.2794 -0.1016)
			(stroke
				(width 0.1)
				(type default)
			)
			(layer "B.Fab")
		)
		(fp_line
			(start -0.2794 -0.1016)
			(end 0.2794 -0.1016)
			(stroke
				(width 0.1)
				(type default)
			)
			(layer "B.Fab")
		)
		(pad "1" smd rect
			(at 0 0)
			(size 0.508 0.508)
			(layers "B.Cu" "B.Mask" "B.Paste")
			(net "P3V3_STBY")
		)
		(pad "2" smd rect
			(at 0 0.889)
			(size 0.508 0.508)
			(layers "B.Cu" "B.Mask" "B.Paste")
			(net "PU_ID_EEPROM_A0")
		)
		(zone
			(layer "B.Cu")
			(hatch none 0.5)
			(connect_pads
				(clearance 0)
			)
			(min_thickness 0.25)
			(keepout
				(tracks not_allowed)
				(vias allowed)
				(pads allowed)
				(copperpour not_allowed)
				(footprints allowed)
			)
			(placement
				(enabled no)
				(sheetname "")
			)
			(fill
				(thermal_gap 0.5)
				(thermal_bridge_width 0.5)
				(island_removal_mode 0)
			)
			(polygon
				(pts
					(xy 462.3435 -23.749) (xy 462.8515 -23.749) (xy 462.8515 -23.368) (xy 462.3435 -23.368)
				)
			)
		)
		(zone
			(layer "B.Cu")
			(hatch none 0.5)
			(connect_pads
				(clearance 0)
			)
			(min_thickness 0.25)
			(keepout
				(tracks allowed)
				(vias not_allowed)
				(pads allowed)
				(copperpour not_allowed)
				(footprints allowed)
			)
			(placement
				(enabled no)
				(sheetname "")
			)
			(fill
				(thermal_gap 0.5)
				(thermal_bridge_width 0.5)
				(island_removal_mode 0)
			)
			(polygon
				(pts
					(xy 462.3435 -23.368) (xy 462.8515 -23.368) (xy 462.8515 -23.749) (xy 462.3435 -23.749)
				)
			)
		)
	)
	(footprint ""
		(layer "B.Cu")
		(at 379.984 -140.589 180)
		(property "Reference" "C3L20"
			(at -3.10007 3.24612 270)
			(unlocked yes)
			(layer "B.SilkS")
			(effects
				(font
					(size 0.7874 0.5842)
					(thickness 0.1524)
				)
				(justify mirror)
			)
		)
		(property "Value" ""
			(at 0 0 0)
			(layer "B.Fab")
			(effects
				(font
					(size 1.27 1.27)
				)
				(justify mirror)
			)
		)
		(duplicate_pad_numbers_are_jumpers no)
		(fp_line
			(start 2.563114 1.633728)
			(end 1.6002 1.633728)
			(stroke
				(width 0.1524)
				(type default)
			)
			(layer "B.SilkS")
		)
		(fp_line
			(start 2.563114 -1.616456)
			(end 2.563114 1.633728)
			(stroke
				(width 0.1524)
				(type default)
			)
			(layer "B.SilkS")
		)
		(fp_line
			(start 2.286 7.366)
			(end 2.286 1.632712)
			(stroke
				(width 0.1524)
				(type default)
			)
			(layer "B.SilkS")
		)
		(fp_line
			(start 2.286 7.366)
			(end 1.60147 7.366)
			(stroke
				(width 0.1524)
				(type default)
			)
			(layer "B.SilkS")
		)
		(fp_line
			(start 1.6002 -1.616456)
			(end 2.563114 -1.616456)
			(stroke
				(width 0.1524)
				(type default)
			)
			(layer "B.SilkS")
		)
		(fp_line
			(start -1.6002 -1.616456)
			(end -2.504948 -1.616456)
			(stroke
				(width 0.1524)
				(type default)
			)
			(layer "B.SilkS")
		)
		(fp_line
			(start -2.286 7.366)
			(end -1.600708 7.366)
			(stroke
				(width 0.1524)
				(type default)
			)
			(layer "B.SilkS")
		)
		(fp_line
			(start -2.286 7.366)
			(end -2.286 1.63195)
			(stroke
				(width 0.1524)
				(type default)
			)
			(layer "B.SilkS")
		)
		(fp_line
			(start -2.504948 1.633728)
			(end -1.6002 1.633728)
			(stroke
				(width 0.1524)
				(type default)
			)
			(layer "B.SilkS")
		)
		(fp_line
			(start -2.504948 -1.616456)
			(end -2.504948 1.633728)
			(stroke
				(width 0.1524)
				(type default)
			)
			(layer "B.SilkS")
		)
		(fp_rect
			(start 2.286 7.366)
			(end -2.286 -0.254)
			(stroke
				(width 0)
				(type default)
			)
			(fill no)
			(layer "B.CrtYd")
		)
		(fp_line
			(start 2.286 7.366)
			(end 2.286 -0.254)
			(stroke
				(width 0.1)
				(type default)
			)
			(layer "B.Fab")
		)
		(fp_line
			(start 2.286 -0.254)
			(end -2.286 -0.254)
			(stroke
				(width 0.1)
				(type default)
			)
			(layer "B.Fab")
		)
		(fp_line
			(start -2.286 7.366)
			(end 2.286 7.366)
			(stroke
				(width 0.1)
				(type default)
			)
			(layer "B.Fab")
		)
		(fp_line
			(start -2.286 -0.254)
			(end -2.286 7.366)
			(stroke
				(width 0.1)
				(type default)
			)
			(layer "B.Fab")
		)
		(pad "1" smd rect
			(at 0 0)
			(size 2.54 3.048)
			(layers "B.Cu" "B.Mask" "B.Paste")
			(net "PVNN_PCH_STBY")
		)
		(pad "2" smd rect
			(at 0 7.112)
			(size 2.54 3.048)
			(layers "B.Cu" "B.Mask" "B.Paste")
			(net "GND")
		)
	)
	(footprint ""
		(layer "B.Cu")
		(at 49.4284 -86.67242)
		(property "Reference" "C9P3"
			(at 0 0 0)
			(layer "B.SilkS")
			(hide yes)
			(effects
				(font
					(size 1.27 1.27)
				)
				(justify mirror)
			)
		)
		(property "Value" ""
			(at 0 0 0)
			(layer "B.Fab")
			(effects
				(font
					(size 1.27 1.27)
				)
				(justify mirror)
			)
		)
		(duplicate_pad_numbers_are_jumpers no)
		(fp_poly
			(pts
				(xy 0.4953 -0.2032) (xy -0.4953 -0.2032) (xy -0.4953 1.6002) (xy 0.4953 1.6002)
			)
			(stroke
				(width 0)
				(type default)
			)
			(fill no)
			(layer "B.CrtYd")
		)
		(fp_line
			(start -0.4953 -0.2032)
			(end -0.4953 1.6002)
			(stroke
				(width 0.1)
				(type default)
			)
			(layer "B.Fab")
		)
		(fp_line
			(start -0.4953 1.6002)
			(end 0.4953 1.6002)
			(stroke
				(width 0.1)
				(type default)
			)
			(layer "B.Fab")
		)
		(fp_line
			(start 0.4953 -0.2032)
			(end -0.4953 -0.2032)
			(stroke
				(width 0.1)
				(type default)
			)
			(layer "B.Fab")
		)
		(fp_line
			(start 0.4953 1.6002)
			(end 0.4953 -0.2032)
			(stroke
				(width 0.1)
				(type default)
			)
			(layer "B.Fab")
		)
		(pad "1" smd rect
			(at 0 0 180)
			(size 0.762 0.889)
			(layers "B.Cu" "B.Mask" "B.Paste")
			(net "PVCCIN_CPU1")
		)
		(pad "2" smd rect
			(at 0 1.397 180)
			(size 0.762 0.889)
			(layers "B.Cu" "B.Mask" "B.Paste")
			(net "GND")
		)
		(zone
			(layer "B.Cu")
			(hatch none 0.5)
			(connect_pads
				(clearance 0)
			)
			(min_thickness 0.25)
			(keepout
				(tracks not_allowed)
				(vias allowed)
				(pads allowed)
				(copperpour not_allowed)
				(footprints allowed)
			)
			(placement
				(enabled no)
				(sheetname "")
			)
			(fill
				(thermal_gap 0.5)
				(thermal_bridge_width 0.5)
				(island_removal_mode 0)
			)
			(polygon
				(pts
					(xy 49.8094 -86.22792) (xy 49.0474 -86.22792) (xy 49.0474 -85.71992) (xy 49.8094 -85.71992)
				)
			)
		)
	)
)
